(kicad_pcb
	(version 20260206)
	(generator "pcbnew")
	(generator_version "10.0")
	(general
		(thickness 1.6)
		(legacy_teardrops no)
	)
	(paper "A4")
	(title_block
		(title "baseboard — 13948-1b.1110WZS1818.brd")
		(comment 1 "Honey Badger (Wiwynn) / footprints 249-257 of 2523")
	)
	(layers
		(0 "F.Cu" signal "TOP")
		(4 "In1.Cu" signal "L2GND")
		(6 "In2.Cu" signal "L3")
		(8 "In3.Cu" signal "L4VCC")
		(10 "In4.Cu" signal "L5VCC")
		(12 "In5.Cu" signal "L6")
		(14 "In6.Cu" signal "L7GND")
		(2 "B.Cu" signal "BOTTOM")
		(9 "F.Adhes" user "F.Adhesive")
		(11 "B.Adhes" user "B.Adhesive")
		(13 "F.Paste" user "Package Geometry/Pastemask Top")
		(15 "B.Paste" user "Package Geometry/Pastemask Bottom")
		(5 "F.SilkS" user "Ref Des/Silkscreen Top")
		(7 "B.SilkS" user "Ref Des/Silkscreen Bottom")
		(1 "F.Mask" user "Board Geometry/Soldermask Top")
		(3 "B.Mask" user "Board Geometry/Soldermask Bottom")
		(17 "Dwgs.User" user "User.Drawings")
		(19 "Cmts.User" user "User.Comments")
		(21 "Eco1.User" user "User.Eco1")
		(23 "Eco2.User" user "User.Eco2")
		(25 "Edge.Cuts" user "Board Geometry/Outline")
		(27 "Margin" user)
		(31 "F.CrtYd" user "Package Geometry/Place Bound Top")
		(29 "B.CrtYd" user "Package Geometry/Place Bound Bottom")
		(35 "F.Fab" user "Ref Des/Assembly Top")
		(33 "B.Fab" user "Ref Des/Assembly Bottom")
	)
	(footprint ""
		(layer "F.Cu")
		(at 339.979 -114.808 -90)
		(property "Reference" "PC11"
			(at 0 0 270)
			(layer "F.SilkS")
			(hide yes)
			(effects
				(font
					(size 1.27 1.27)
				)
			)
		)
		(property "Value" "SC3300P50V2KX-1GP"
			(at 1.1811 -2.7051 270)
			(unlocked yes)
			(layer "F.Fab")
			(hide yes)
			(effects
				(font
					(size 1.016 1.016)
					(thickness 0.1524)
				)
			)
		)
		(property "Device Type" "C402H22"
			(at 1.1811 -4.2291 270)
			(unlocked yes)
			(layer "F.Fab")
			(hide yes)
			(effects
				(font
					(size 1.016 1.016)
					(thickness 0.1524)
				)
			)
		)
		(duplicate_pad_numbers_are_jumpers no)
		(fp_rect
			(start -0.4318 0.9525)
			(end 0.4318 -0.9525)
			(stroke
				(width 0)
				(type default)
			)
			(fill no)
			(layer "F.CrtYd")
		)
		(fp_rect
			(start -0.4318 0.9525)
			(end 0.4318 -0.9525)
			(stroke
				(width 0)
				(type default)
			)
			(fill no)
			(layer "F.Fab")
		)
		(pad "1" smd custom
			(at 0 -0.4445 270)
			(size 0.1524 0.1524)
			(layers "F.Cu" "F.Mask" "F.Paste")
			(net "P5V_STBY_SS")
			(options
				(clearance outline)
				(anchor circle)
			)
			(primitives
				(gr_poly
					(pts
						(arc
							(start 0.3048 -0.2032)
							(mid 0.275042 -0.275042)
							(end 0.2032 -0.3048)
						)
						(arc
							(start -0.2032 -0.3048)
							(mid -0.275042 -0.275042)
							(end -0.3048 -0.2032)
						)
						(arc
							(start -0.3048 0.2032)
							(mid -0.275042 0.275042)
							(end -0.2032 0.3048)
						)
						(arc
							(start 0.2032 0.3048)
							(mid 0.275042 0.275042)
							(end 0.3048 0.2032)
						)
					)
					(width 0)
					(fill yes)
				)
			)
		)
		(pad "2" smd custom
			(at 0 0.4445 270)
			(size 0.1524 0.1524)
			(layers "F.Cu" "F.Mask" "F.Paste")
			(net "AGND_P5V_STBY")
			(options
				(clearance outline)
				(anchor circle)
			)
			(primitives
				(gr_poly
					(pts
						(arc
							(start 0.3048 -0.2032)
							(mid 0.275042 -0.275042)
							(end 0.2032 -0.3048)
						)
						(arc
							(start -0.2032 -0.3048)
							(mid -0.275042 -0.275042)
							(end -0.3048 -0.2032)
						)
						(arc
							(start -0.3048 0.2032)
							(mid -0.275042 0.275042)
							(end -0.2032 0.3048)
						)
						(arc
							(start 0.2032 0.3048)
							(mid 0.275042 0.275042)
							(end 0.3048 0.2032)
						)
					)
					(width 0)
					(fill yes)
				)
			)
		)
	)
	(footprint ""
		(layer "F.Cu")
		(at 333.912718 -153.393648 -90)
		(property "Reference" "C155"
			(at 0 0 270)
			(layer "F.SilkS")
			(hide yes)
			(effects
				(font
					(size 1.27 1.27)
				)
			)
		)
		(property "Value" "SC1U10V2KX-4-GP"
			(at 1.1811 -2.7051 270)
			(unlocked yes)
			(layer "F.Fab")
			(hide yes)
			(effects
				(font
					(size 1.016 1.016)
					(thickness 0.1524)
				)
			)
		)
		(property "Device Type" "C402H22"
			(at 1.1811 -4.2291 270)
			(unlocked yes)
			(layer "F.Fab")
			(hide yes)
			(effects
				(font
					(size 1.016 1.016)
					(thickness 0.1524)
				)
			)
		)
		(duplicate_pad_numbers_are_jumpers no)
		(fp_rect
			(start -0.4318 0.9525)
			(end 0.4318 -0.9525)
			(stroke
				(width 0)
				(type default)
			)
			(fill no)
			(layer "F.CrtYd")
		)
		(fp_rect
			(start -0.4318 0.9525)
			(end 0.4318 -0.9525)
			(stroke
				(width 0)
				(type default)
			)
			(fill no)
			(layer "F.Fab")
		)
		(pad "1" smd custom
			(at 0 -0.4445 270)
			(size 0.1524 0.1524)
			(layers "F.Cu" "F.Mask" "F.Paste")
			(net "P3V3_STBY")
			(options
				(clearance outline)
				(anchor circle)
			)
			(primitives
				(gr_poly
					(pts
						(arc
							(start 0.3048 -0.2032)
							(mid 0.275042 -0.275042)
							(end 0.2032 -0.3048)
						)
						(arc
							(start -0.2032 -0.3048)
							(mid -0.275042 -0.275042)
							(end -0.3048 -0.2032)
						)
						(arc
							(start -0.3048 0.2032)
							(mid -0.275042 0.275042)
							(end -0.2032 0.3048)
						)
						(arc
							(start 0.2032 0.3048)
							(mid 0.275042 0.275042)
							(end 0.3048 0.2032)
						)
					)
					(width 0)
					(fill yes)
				)
			)
		)
		(pad "2" smd custom
			(at 0 0.4445 270)
			(size 0.1524 0.1524)
			(layers "F.Cu" "F.Mask" "F.Paste")
			(net "GND")
			(options
				(clearance outline)
				(anchor circle)
			)
			(primitives
				(gr_poly
					(pts
						(arc
							(start 0.3048 -0.2032)
							(mid 0.275042 -0.275042)
							(end 0.2032 -0.3048)
						)
						(arc
							(start -0.2032 -0.3048)
							(mid -0.275042 -0.275042)
							(end -0.3048 -0.2032)
						)
						(arc
							(start -0.3048 0.2032)
							(mid -0.275042 0.275042)
							(end -0.2032 0.3048)
						)
						(arc
							(start 0.2032 0.3048)
							(mid 0.275042 0.275042)
							(end 0.3048 0.2032)
						)
					)
					(width 0)
					(fill yes)
				)
			)
		)
	)
	(footprint ""
		(layer "F.Cu")
		(at 176.03597 -66.421)
		(property "Reference" "TP149"
			(at 0 0 0)
			(layer "F.SilkS")
			(hide yes)
			(effects
				(font
					(size 1.27 1.27)
				)
			)
		)
		(property "Value" "TPAD28"
			(at 0.0127 -1.8034 0)
			(unlocked yes)
			(layer "F.Fab")
			(hide yes)
			(effects
				(font
					(size 1.016 1.016)
					(thickness 0.1524)
				)
			)
		)
		(property "Device Type" "TPAD28"
			(at 0.0127 -3.3274 0)
			(unlocked yes)
			(layer "F.Fab")
			(hide yes)
			(effects
				(font
					(size 1.016 1.016)
					(thickness 0.1524)
				)
			)
		)
		(duplicate_pad_numbers_are_jumpers no)
		(fp_poly
			(pts
				(arc
					(start 0.3556 0)
					(mid -0.3556 0)
					(end 0.3556 0)
				)
			)
			(stroke
				(width 0)
				(type default)
			)
			(fill no)
			(layer "F.CrtYd")
		)
		(fp_poly
			(pts
				(arc
					(start 0.6096 0)
					(mid -0.6096 0)
					(end 0.6096 0)
				)
			)
			(stroke
				(width 0)
				(type default)
			)
			(fill no)
			(layer "F.Fab")
		)
		(pad "1" smd circle
			(at 0 0)
			(size 0.7112 0.7112)
			(layers "F.Cu" "F.Mask" "F.Paste")
			(net "TP_MSB_A41")
		)
	)
	(footprint ""
		(layer "F.Cu")
		(at 217.12428 -87.98052 180)
		(property "Reference" "SC1098"
			(at 0 0 180)
			(layer "F.SilkS")
			(hide yes)
			(effects
				(font
					(size 1.27 1.27)
				)
			)
		)
		(property "Value" "SCD1U16V2KX-3GP"
			(at 1.1811 -2.7051 180)
			(unlocked yes)
			(layer "F.Fab")
			(hide yes)
			(effects
				(font
					(size 1.016 1.016)
					(thickness 0.1524)
				)
			)
		)
		(property "Device Type" "C402H22"
			(at 1.1811 -4.2291 180)
			(unlocked yes)
			(layer "F.Fab")
			(hide yes)
			(effects
				(font
					(size 1.016 1.016)
					(thickness 0.1524)
				)
			)
		)
		(duplicate_pad_numbers_are_jumpers no)
		(fp_rect
			(start -0.4318 0.9525)
			(end 0.4318 -0.9525)
			(stroke
				(width 0)
				(type default)
			)
			(fill no)
			(layer "F.CrtYd")
		)
		(fp_rect
			(start -0.4318 0.9525)
			(end 0.4318 -0.9525)
			(stroke
				(width 0)
				(type default)
			)
			(fill no)
			(layer "F.Fab")
		)
		(pad "1" smd custom
			(at 0 -0.4445 180)
			(size 0.1524 0.1524)
			(layers "F.Cu" "F.Mask" "F.Paste")
			(net "P1V8_C")
			(options
				(clearance outline)
				(anchor circle)
			)
			(primitives
				(gr_poly
					(pts
						(arc
							(start 0.3048 -0.2032)
							(mid 0.275042 -0.275042)
							(end 0.2032 -0.3048)
						)
						(arc
							(start -0.2032 -0.3048)
							(mid -0.275042 -0.275042)
							(end -0.3048 -0.2032)
						)
						(arc
							(start -0.3048 0.2032)
							(mid -0.275042 0.275042)
							(end -0.2032 0.3048)
						)
						(arc
							(start 0.2032 0.3048)
							(mid 0.275042 0.275042)
							(end 0.3048 0.2032)
						)
					)
					(width 0)
					(fill yes)
				)
			)
		)
		(pad "2" smd custom
			(at 0 0.4445 180)
			(size 0.1524 0.1524)
			(layers "F.Cu" "F.Mask" "F.Paste")
			(net "GND")
			(options
				(clearance outline)
				(anchor circle)
			)
			(primitives
				(gr_poly
					(pts
						(arc
							(start 0.3048 -0.2032)
							(mid 0.275042 -0.275042)
							(end 0.2032 -0.3048)
						)
						(arc
							(start -0.2032 -0.3048)
							(mid -0.275042 -0.275042)
							(end -0.3048 -0.2032)
						)
						(arc
							(start -0.3048 0.2032)
							(mid -0.275042 0.275042)
							(end -0.2032 0.3048)
						)
						(arc
							(start 0.2032 0.3048)
							(mid 0.275042 0.275042)
							(end 0.3048 0.2032)
						)
					)
					(width 0)
					(fill yes)
				)
			)
		)
	)
	(footprint ""
		(layer "F.Cu")
		(at 78.73619 -56.228488 -90)
		(property "Reference" "SC929"
			(at 0 0 270)
			(layer "F.SilkS")
			(hide yes)
			(effects
				(font
					(size 1.27 1.27)
				)
			)
		)
		(property "Value" "SC1U6D3V1MX-GP"
			(at 1.9177 2.0193 270)
			(unlocked yes)
			(layer "F.Fab")
			(hide yes)
			(effects
				(font
					(size 1.016 1.016)
					(thickness 0.1524)
				)
			)
		)
		(property "Device Type" "C0201H14"
			(at 1.9177 0.4953 270)
			(unlocked yes)
			(layer "F.Fab")
			(hide yes)
			(effects
				(font
					(size 1.016 1.016)
					(thickness 0.1524)
				)
			)
		)
		(duplicate_pad_numbers_are_jumpers no)
		(fp_rect
			(start -0.1524 0.3048)
			(end 0.1524 -0.3048)
			(stroke
				(width 0)
				(type default)
			)
			(fill no)
			(layer "F.CrtYd")
		)
		(fp_poly
			(pts
				(xy -0.2794 0.6477) (xy -0.2794 -0.6477) (xy 0.2794 -0.6477) (xy 0.2794 -0.1905) (xy 0.1524 -0.1905)
				(xy 0.1524 -0.3048) (xy -0.1524 -0.3048) (xy -0.1524 0.3048) (xy 0.1524 0.3048) (xy 0.1524 -0.1778)
				(xy 0.2794 -0.1778) (xy 0.2794 0.6477)
			)
			(stroke
				(width 0)
				(type default)
			)
			(fill no)
			(layer "F.CrtYd")
		)
		(fp_rect
			(start -0.2794 0.6477)
			(end 0.2794 -0.6477)
			(stroke
				(width 0)
				(type default)
			)
			(fill no)
			(layer "F.Fab")
		)
		(pad "1" smd custom
			(at 0 -0.2794 270)
			(size 0.0762 0.0762)
			(layers "F.Cu" "F.Mask" "F.Paste")
			(net "SHELL_PLL_VDD")
			(options
				(clearance outline)
				(anchor circle)
			)
			(primitives
				(gr_poly
					(pts
						(arc
							(start 0.1524 -0.127)
							(mid 0.137521 -0.162921)
							(end 0.1016 -0.1778)
						)
						(arc
							(start -0.1016 -0.1778)
							(mid -0.137521 -0.162921)
							(end -0.1524 -0.127)
						)
						(arc
							(start -0.1524 0.127)
							(mid -0.137521 0.162921)
							(end -0.1016 0.1778)
						)
						(arc
							(start 0.1016 0.1778)
							(mid 0.137521 0.162921)
							(end 0.1524 0.127)
						)
					)
					(width 0)
					(fill yes)
				)
			)
		)
		(pad "2" smd custom
			(at 0 0.2794 270)
			(size 0.0762 0.0762)
			(layers "F.Cu" "F.Mask" "F.Paste")
			(net "GND")
			(options
				(clearance outline)
				(anchor circle)
			)
			(primitives
				(gr_poly
					(pts
						(arc
							(start 0.1524 -0.127)
							(mid 0.137521 -0.162921)
							(end 0.1016 -0.1778)
						)
						(arc
							(start -0.1016 -0.1778)
							(mid -0.137521 -0.162921)
							(end -0.1524 -0.127)
						)
						(arc
							(start -0.1524 0.127)
							(mid -0.137521 0.162921)
							(end -0.1016 0.1778)
						)
						(arc
							(start 0.1016 0.1778)
							(mid 0.137521 0.162921)
							(end 0.1524 0.127)
						)
					)
					(width 0)
					(fill yes)
				)
			)
		)
	)
	(footprint ""
		(layer "F.Cu")
		(at 89.643966 -63.119)
		(property "Reference" "SR678"
			(at 0 0 0)
			(layer "F.SilkS")
			(hide yes)
			(effects
				(font
					(size 1.27 1.27)
				)
			)
		)
		(property "Value" "4K7R2F-GP"
			(at 0.064008 -3.993896 0)
			(unlocked yes)
			(layer "F.Fab")
			(hide yes)
			(effects
				(font
					(size 1.016 1.016)
					(thickness 0.1524)
				)
			)
		)
		(property "Device Type" "R402H16"
			(at 0.064008 -5.517896 0)
			(unlocked yes)
			(layer "F.Fab")
			(hide yes)
			(effects
				(font
					(size 1.016 1.016)
					(thickness 0.1524)
				)
			)
		)
		(duplicate_pad_numbers_are_jumpers no)
		(fp_line
			(start -0.508 -0.9398)
			(end -0.508 0.9398)
			(stroke
				(width 0.1524)
				(type default)
			)
			(layer "F.SilkS")
		)
		(fp_line
			(start 0.508 -0.9398)
			(end -0.508 -0.9398)
			(stroke
				(width 0.1524)
				(type default)
			)
			(layer "F.SilkS")
		)
		(fp_rect
			(start -0.508 0.9398)
			(end 0.508 -0.9398)
			(stroke
				(width 0)
				(type default)
			)
			(fill no)
			(layer "F.CrtYd")
		)
		(fp_rect
			(start -0.508 0.9398)
			(end 0.508 -0.9398)
			(stroke
				(width 0)
				(type default)
			)
			(fill no)
			(layer "F.Fab")
		)
		(pad "1" smd custom
			(at 0 -0.4445)
			(size 0.1397 0.1397)
			(layers "F.Cu" "F.Mask" "F.Paste")
			(net "P1V8_C")
			(options
				(clearance outline)
				(anchor circle)
			)
			(primitives
				(gr_poly
					(pts
						(arc
							(start -0.1778 -0.2794)
							(mid -0.249642 -0.249642)
							(end -0.2794 -0.1778)
						)
						(arc
							(start -0.2794 0.1778)
							(mid -0.249642 0.249642)
							(end -0.1778 0.2794)
						)
						(arc
							(start 0.1778 0.2794)
							(mid 0.249642 0.249642)
							(end 0.2794 0.1778)
						)
						(arc
							(start 0.2794 -0.1778)
							(mid 0.249642 -0.249642)
							(end 0.1778 -0.2794)
						)
					)
					(width 0)
					(fill yes)
				)
			)
		)
		(pad "2" smd custom
			(at 0 0.4445)
			(size 0.1397 0.1397)
			(layers "F.Cu" "F.Mask" "F.Paste")
			(net "ICE0_TMS")
			(options
				(clearance outline)
				(anchor circle)
			)
			(primitives
				(gr_poly
					(pts
						(arc
							(start -0.1778 -0.2794)
							(mid -0.249642 -0.249642)
							(end -0.2794 -0.1778)
						)
						(arc
							(start -0.2794 0.1778)
							(mid -0.249642 0.249642)
							(end -0.1778 0.2794)
						)
						(arc
							(start 0.1778 0.2794)
							(mid 0.249642 0.249642)
							(end 0.2794 0.1778)
						)
						(arc
							(start 0.2794 -0.1778)
							(mid 0.249642 -0.249642)
							(end 0.1778 -0.2794)
						)
					)
					(width 0)
					(fill yes)
				)
			)
		)
	)
	(footprint ""
		(layer "F.Cu")
		(at 301.752 -161.163)
		(property "Reference" "TP92"
			(at 0 0 0)
			(layer "F.SilkS")
			(hide yes)
			(effects
				(font
					(size 1.27 1.27)
				)
			)
		)
		(property "Value" "TPAD28"
			(at 0.0127 -1.8034 0)
			(unlocked yes)
			(layer "F.Fab")
			(hide yes)
			(effects
				(font
					(size 1.016 1.016)
					(thickness 0.1524)
				)
			)
		)
		(property "Device Type" "TPAD28"
			(at 0.0127 -3.3274 0)
			(unlocked yes)
			(layer "F.Fab")
			(hide yes)
			(effects
				(font
					(size 1.016 1.016)
					(thickness 0.1524)
				)
			)
		)
		(duplicate_pad_numbers_are_jumpers no)
		(fp_poly
			(pts
				(arc
					(start 0.3556 0)
					(mid -0.3556 0)
					(end 0.3556 0)
				)
			)
			(stroke
				(width 0)
				(type default)
			)
			(fill no)
			(layer "F.CrtYd")
		)
		(fp_poly
			(pts
				(arc
					(start 0.6096 0)
					(mid -0.6096 0)
					(end 0.6096 0)
				)
			)
			(stroke
				(width 0)
				(type default)
			)
			(fill no)
			(layer "F.Fab")
		)
		(pad "1" smd circle
			(at 0 0)
			(size 0.7112 0.7112)
			(layers "F.Cu" "F.Mask" "F.Paste")
			(net "TP_GPIOH3")
		)
	)
	(footprint ""
		(layer "F.Cu")
		(at 301.117 -162.433)
		(property "Reference" "TP95"
			(at 0 0 0)
			(layer "F.SilkS")
			(hide yes)
			(effects
				(font
					(size 1.27 1.27)
				)
			)
		)
		(property "Value" "TPAD28"
			(at 0.0127 -1.8034 0)
			(unlocked yes)
			(layer "F.Fab")
			(hide yes)
			(effects
				(font
					(size 1.016 1.016)
					(thickness 0.1524)
				)
			)
		)
		(property "Device Type" "TPAD28"
			(at 0.0127 -3.3274 0)
			(unlocked yes)
			(layer "F.Fab")
			(hide yes)
			(effects
				(font
					(size 1.016 1.016)
					(thickness 0.1524)
				)
			)
		)
		(duplicate_pad_numbers_are_jumpers no)
		(fp_poly
			(pts
				(arc
					(start 0.3556 0)
					(mid -0.3556 0)
					(end 0.3556 0)
				)
			)
			(stroke
				(width 0)
				(type default)
			)
			(fill no)
			(layer "F.CrtYd")
		)
		(fp_poly
			(pts
				(arc
					(start 0.6096 0)
					(mid -0.6096 0)
					(end 0.6096 0)
				)
			)
			(stroke
				(width 0)
				(type default)
			)
			(fill no)
			(layer "F.Fab")
		)
		(pad "1" smd circle
			(at 0 0)
			(size 0.7112 0.7112)
			(layers "F.Cu" "F.Mask" "F.Paste")
			(net "TP_GPIOH6")
		)
	)
	(footprint ""
		(layer "F.Cu")
		(at 304.918872 -204.288136 -90)
		(property "Reference" "C142"
			(at 0 0 270)
			(layer "F.SilkS")
			(hide yes)
			(effects
				(font
					(size 1.27 1.27)
				)
			)
		)
		(property "Value" "SCD1U16V2KX-3GP"
			(at 1.1811 -2.7051 270)
			(unlocked yes)
			(layer "F.Fab")
			(hide yes)
			(effects
				(font
					(size 1.016 1.016)
					(thickness 0.1524)
				)
			)
		)
		(property "Device Type" "C402H22"
			(at 1.1811 -4.2291 270)
			(unlocked yes)
			(layer "F.Fab")
			(hide yes)
			(effects
				(font
					(size 1.016 1.016)
					(thickness 0.1524)
				)
			)
		)
		(duplicate_pad_numbers_are_jumpers no)
		(fp_rect
			(start -0.4318 0.9525)
			(end 0.4318 -0.9525)
			(stroke
				(width 0)
				(type default)
			)
			(fill no)
			(layer "F.CrtYd")
		)
		(fp_rect
			(start -0.4318 0.9525)
			(end 0.4318 -0.9525)
			(stroke
				(width 0)
				(type default)
			)
			(fill no)
			(layer "F.Fab")
		)
		(pad "1" smd custom
			(at 0 -0.4445 270)
			(size 0.1524 0.1524)
			(layers "F.Cu" "F.Mask" "F.Paste")
			(net "P3V3_STBY")
			(options
				(clearance outline)
				(anchor circle)
			)
			(primitives
				(gr_poly
					(pts
						(arc
							(start 0.3048 -0.2032)
							(mid 0.275042 -0.275042)
							(end 0.2032 -0.3048)
						)
						(arc
							(start -0.2032 -0.3048)
							(mid -0.275042 -0.275042)
							(end -0.3048 -0.2032)
						)
						(arc
							(start -0.3048 0.2032)
							(mid -0.275042 0.275042)
							(end -0.2032 0.3048)
						)
						(arc
							(start 0.2032 0.3048)
							(mid 0.275042 0.275042)
							(end 0.3048 0.2032)
						)
					)
					(width 0)
					(fill yes)
				)
			)
		)
		(pad "2" smd custom
			(at 0 0.4445 270)
			(size 0.1524 0.1524)
			(layers "F.Cu" "F.Mask" "F.Paste")
			(net "GND")
			(options
				(clearance outline)
				(anchor circle)
			)
			(primitives
				(gr_poly
					(pts
						(arc
							(start 0.3048 -0.2032)
							(mid 0.275042 -0.275042)
							(end 0.2032 -0.3048)
						)
						(arc
							(start -0.2032 -0.3048)
							(mid -0.275042 -0.275042)
							(end -0.3048 -0.2032)
						)
						(arc
							(start -0.3048 0.2032)
							(mid -0.275042 0.275042)
							(end -0.2032 0.3048)
						)
						(arc
							(start 0.2032 0.3048)
							(mid 0.275042 0.275042)
							(end 0.3048 0.2032)
						)
					)
					(width 0)
					(fill yes)
				)
			)
		)
	)
)
